(kicad_pcb
	(version 20260206)
	(generator "pcbnew")
	(generator_version "10.0")
	(general
		(thickness 1.6)
		(legacy_teardrops no)
	)
	(paper "A4")
	(title_block
		(title "v1-chassis-manager — T6M_CM_d_v01_1031_1645.brd")
		(comment 1 "Open CloudServer (Microsoft) / footprint 1295 of 2512 (U1), pads 1-57 of 57")
	)
	(layers
		(0 "F.Cu" signal "TOP")
		(4 "In1.Cu" signal "GND1")
		(6 "In2.Cu" signal "IN1")
		(8 "In3.Cu" signal "VCC1")
		(10 "In4.Cu" signal "VCC2")
		(12 "In5.Cu" signal "GND2")
		(14 "In6.Cu" signal "IN2")
		(16 "In7.Cu" signal "IN3")
		(18 "In8.Cu" signal "GND3")
		(2 "B.Cu" signal "BOTTOM")
		(9 "F.Adhes" user "F.Adhesive")
		(11 "B.Adhes" user "B.Adhesive")
		(13 "F.Paste" user "Package Geometry/Pastemask Top")
		(15 "B.Paste" user "Package Geometry/Pastemask Bottom")
		(5 "F.SilkS" user "Ref Des/Silkscreen Top")
		(7 "B.SilkS" user "Ref Des/Silkscreen Bottom")
		(1 "F.Mask" user "Board Geometry/Soldermask Top")
		(3 "B.Mask" user "Board Geometry/Soldermask Bottom")
		(17 "Dwgs.User" user "User.Drawings")
		(19 "Cmts.User" user "User.Comments")
		(21 "Eco1.User" user "User.Eco1")
		(23 "Eco2.User" user "User.Eco2")
		(25 "Edge.Cuts" user "Board Geometry/Outline")
		(27 "Margin" user)
		(31 "F.CrtYd" user "Package Geometry/Place Bound Top")
		(29 "B.CrtYd" user "Package Geometry/Place Bound Bottom")
		(35 "F.Fab" user "Ref Des/Assembly Top")
		(33 "B.Fab" user "Ref Des/Assembly Bottom")
	)
	(footprint ""
		(layer "F.Cu")
		(at 132.95376 -117.514624 90)
		(property "Reference" "U1"
			(at 5.298948 -1.346708 0)
			(unlocked yes)
			(layer "F.SilkS")
			(effects
				(font
					(size 0.7874 0.5842)
					(thickness 0.1524)
				)
				(justify left)
			)
		)
		(property "Value" ""
			(at 0 0 90)
			(layer "F.Fab")
			(effects
				(font
					(size 1.27 1.27)
				)
			)
		)
		(duplicate_pad_numbers_are_jumpers no)
		(pad "1" smd rect
			(at -3.549904 -2.599944)
			(size 0.1778 0.889)
			(layers "F.Cu" "F.Mask" "F.Paste")
			(net "XTAL_CLK_NODE1_X2")
		)
		(pad "2" smd rect
			(at -3.549904 -2.199894)
			(size 0.1778 0.889)
			(layers "F.Cu" "F.Mask" "F.Paste")
			(net "XTAL_CLK_NODE1_X1")
		)
		(pad "3" smd rect
			(at -3.549904 -1.800098)
			(size 0.1778 0.889)
			(layers "F.Cu" "F.Mask" "F.Paste")
			(net "P3V3_CLK_NODE1")
		)
		(pad "4" smd rect
			(at -3.549904 -1.400048)
			(size 0.1778 0.889)
			(layers "F.Cu" "F.Mask" "F.Paste")
			(net "CLK_25M_SATA_NODE1_R")
		)
		(pad "5" smd rect
			(at -3.549904 -0.999998)
			(size 0.1778 0.889)
			(layers "F.Cu" "F.Mask" "F.Paste")
			(net "SMB_MUX_CPU_ICS_NODE1_DAT")
		)
		(pad "6" smd rect
			(at -3.549904 -0.599948)
			(size 0.1778 0.889)
			(layers "F.Cu" "F.Mask" "F.Paste")
			(net "SMB_MUX_CPU_ICS_NODE1_CLK")
		)
		(pad "7" smd rect
			(at -3.549904 -0.199898)
			(size 0.1778 0.889)
			(layers "F.Cu" "F.Mask" "F.Paste")
			(net "P3V3_CLK_NODE1")
		)
		(pad "8" smd rect
			(at -3.549904 0.199898)
			(size 0.1778 0.889)
			(layers "F.Cu" "F.Mask" "F.Paste")
			(net "CLP_ITP_EN_NODE1")
		)
		(pad "9" smd rect
			(at -3.549904 0.599948)
			(size 0.1778 0.889)
			(layers "F.Cu" "F.Mask" "F.Paste")
			(net "CLK_FSLB_NODE1")
		)
		(pad "10" smd rect
			(at -3.549904 0.999998)
			(size 0.1778 0.889)
			(layers "F.Cu" "F.Mask" "F.Paste")
			(net "CLKREQA_NODE1_N")
		)
		(pad "11" smd rect
			(at -3.549904 1.400048)
			(size 0.1778 0.889)
			(layers "F.Cu" "F.Mask" "F.Paste")
			(net "GND")
		)
		(pad "12" smd rect
			(at -3.549904 1.800098)
			(size 0.1778 0.889)
			(layers "F.Cu" "F.Mask" "F.Paste")
			(net "GND")
		)
		(pad "13" smd rect
			(at -3.549904 2.199894)
			(size 0.1778 0.889)
			(layers "F.Cu" "F.Mask" "F.Paste")
			(net "CLK_14M_CPU_NODE1_R")
		)
		(pad "14" smd rect
			(at -3.549904 2.599944)
			(size 0.1778 0.889)
			(layers "F.Cu" "F.Mask" "F.Paste")
			(net "P3V3_CLK_NODE1")
		)
		(pad "15" smd rect
			(at -2.599944 3.549904 90)
			(size 0.1778 0.889)
			(layers "F.Cu" "F.Mask" "F.Paste")
			(net "P3V3_CLK_NODE1")
		)
		(pad "16" smd rect
			(at -2.199894 3.549904 90)
			(size 0.1778 0.889)
			(layers "F.Cu" "F.Mask" "F.Paste")
			(net "SEL_DOT_SRC5")
		)
		(pad "17" smd rect
			(at -1.800098 3.549904 90)
			(size 0.1778 0.889)
			(layers "F.Cu" "F.Mask" "F.Paste")
			(net "CLKREQC_NODE1_N")
		)
		(pad "18" smd rect
			(at -1.400048 3.549904 90)
			(size 0.1778 0.889)
			(layers "F.Cu" "F.Mask" "F.Paste")
			(net "GND")
		)
		(pad "19" smd rect
			(at -0.999998 3.549904 90)
			(size 0.1778 0.889)
			(layers "F.Cu" "F.Mask" "F.Paste")
			(net "CLKREQB_NODE1_N")
		)
		(pad "20" smd rect
			(at -0.599948 3.549904 90)
			(size 0.1778 0.889)
			(layers "F.Cu" "F.Mask" "F.Paste")
			(net "P3V3_CLK_NODE1")
		)
		(pad "21" smd rect
			(at -0.199898 3.549904 90)
			(size 0.1778 0.889)
			(layers "F.Cu" "F.Mask" "F.Paste")
			(net "SEL_PCI_27M")
		)
		(pad "22" smd rect
			(at 0.199898 3.549904 90)
			(size 0.1778 0.889)
			(layers "F.Cu" "F.Mask" "F.Paste")
			(net "GND")
		)
		(pad "23" smd rect
			(at 0.599948 3.549904 90)
			(size 0.1778 0.889)
			(layers "F.Cu" "F.Mask" "F.Paste")
			(net "CLK_100M_PCIE_SW_NODE1_DP")
		)
		(pad "24" smd rect
			(at 0.999998 3.549904 90)
			(size 0.1778 0.889)
			(layers "F.Cu" "F.Mask" "F.Paste")
			(net "CLK_100M_PCIE_SW_NODE1_DN")
		)
		(pad "25" smd rect
			(at 1.400048 3.549904 90)
			(size 0.1778 0.889)
			(layers "F.Cu" "F.Mask" "F.Paste")
			(net "P1V5_CLK_NODE1")
		)
		(pad "26" smd rect
			(at 1.800098 3.549904 90)
			(size 0.1778 0.889)
			(layers "F.Cu" "F.Mask" "F.Paste")
			(net "Net_1702")
		)
		(pad "27" smd rect
			(at 2.199894 3.549904 90)
			(size 0.1778 0.889)
			(layers "F.Cu" "F.Mask" "F.Paste")
			(net "Net_1701")
		)
		(pad "28" smd rect
			(at 2.599944 3.549904 90)
			(size 0.1778 0.889)
			(layers "F.Cu" "F.Mask" "F.Paste")
			(net "GND")
		)
		(pad "29" smd rect
			(at 3.549904 2.599944)
			(size 0.1778 0.889)
			(layers "F.Cu" "F.Mask" "F.Paste")
			(net "GND")
		)
		(pad "30" smd rect
			(at 3.549904 2.199894)
			(size 0.1778 0.889)
			(layers "F.Cu" "F.Mask" "F.Paste")
			(net "CLK_100M_SATA_NODE1_DN")
		)
		(pad "31" smd rect
			(at 3.549904 1.800098)
			(size 0.1778 0.889)
			(layers "F.Cu" "F.Mask" "F.Paste")
			(net "CLK_100M_SATA_NODE1_DP")
		)
		(pad "32" smd rect
			(at 3.549904 1.400048)
			(size 0.1778 0.889)
			(layers "F.Cu" "F.Mask" "F.Paste")
			(net "CLK_100M_NIC2_NODE1_DN")
		)
		(pad "33" smd rect
			(at 3.549904 0.999998)
			(size 0.1778 0.889)
			(layers "F.Cu" "F.Mask" "F.Paste")
			(net "CLK_100M_NIC2_NODE1_DP")
		)
		(pad "34" smd rect
			(at 3.549904 0.599948)
			(size 0.1778 0.889)
			(layers "F.Cu" "F.Mask" "F.Paste")
			(net "P1V05_CLK_NODE1")
		)
		(pad "35" smd rect
			(at 3.549904 0.199898)
			(size 0.1778 0.889)
			(layers "F.Cu" "F.Mask" "F.Paste")
			(net "PCI_STP_NODE1")
		)
		(pad "36" smd rect
			(at 3.549904 -0.199898)
			(size 0.1778 0.889)
			(layers "F.Cu" "F.Mask" "F.Paste")
			(net "CLK_100M_NIC1_NODE1_DN")
		)
		(pad "37" smd rect
			(at 3.549904 -0.599948)
			(size 0.1778 0.889)
			(layers "F.Cu" "F.Mask" "F.Paste")
			(net "CLK_100M_NIC1_NODE1_DP")
		)
		(pad "38" smd rect
			(at 3.549904 -0.999998)
			(size 0.1778 0.889)
			(layers "F.Cu" "F.Mask" "F.Paste")
			(net "CLK_100M_USB_NODE1_DN")
		)
		(pad "39" smd rect
			(at 3.549904 -1.400048)
			(size 0.1778 0.889)
			(layers "F.Cu" "F.Mask" "F.Paste")
			(net "CLK_100M_USB_NODE1_DP")
		)
		(pad "40" smd rect
			(at 3.549904 -1.800098)
			(size 0.1778 0.889)
			(layers "F.Cu" "F.Mask" "F.Paste")
			(net "GND")
		)
		(pad "41" smd rect
			(at 3.549904 -2.199894)
			(size 0.1778 0.889)
			(layers "F.Cu" "F.Mask" "F.Paste")
			(net "CLK_100M_PCIE_RP0_NODE1_DN")
		)
		(pad "42" smd rect
			(at 3.549904 -2.599944)
			(size 0.1778 0.889)
			(layers "F.Cu" "F.Mask" "F.Paste")
			(net "CLK_100M_PCIE_RP0_NODE1_DP")
		)
		(pad "43" smd rect
			(at 2.599944 -3.549904 90)
			(size 0.1778 0.889)
			(layers "F.Cu" "F.Mask" "F.Paste")
			(net "CLK_100M_BMC_NODE1_DN")
		)
		(pad "44" smd rect
			(at 2.199894 -3.549904 90)
			(size 0.1778 0.889)
			(layers "F.Cu" "F.Mask" "F.Paste")
			(net "CLK_100M_BMC_NODE1_DP")
		)
		(pad "45" smd rect
			(at 1.800098 -3.549904 90)
			(size 0.1778 0.889)
			(layers "F.Cu" "F.Mask" "F.Paste")
			(net "CPU_STP_NODE1")
		)
		(pad "46" smd rect
			(at 1.400048 -3.549904 90)
			(size 0.1778 0.889)
			(layers "F.Cu" "F.Mask" "F.Paste")
			(net "CLK_100M_XDP_NODE1_DN")
		)
		(pad "47" smd rect
			(at 0.999998 -3.549904 90)
			(size 0.1778 0.889)
			(layers "F.Cu" "F.Mask" "F.Paste")
			(net "CLK_100M_XDP_NODE1_DP")
		)
		(pad "48" smd rect
			(at 0.599948 -3.549904 90)
			(size 0.1778 0.889)
			(layers "F.Cu" "F.Mask" "F.Paste")
			(net "P1V5_CLK_NODE1")
		)
		(pad "49" smd rect
			(at 0.199898 -3.549904 90)
			(size 0.1778 0.889)
			(layers "F.Cu" "F.Mask" "F.Paste")
			(net "P1V05_CLK_NODE1")
		)
		(pad "50" smd rect
			(at -0.199898 -3.549904 90)
			(size 0.1778 0.889)
			(layers "F.Cu" "F.Mask" "F.Paste")
			(net "CLK_100M_CPU_NODE1_DN")
		)
		(pad "51" smd rect
			(at -0.599948 -3.549904 90)
			(size 0.1778 0.889)
			(layers "F.Cu" "F.Mask" "F.Paste")
			(net "CLK_100M_CPU_NODE1_DP")
		)
		(pad "52" smd rect
			(at -0.999998 -3.549904 90)
			(size 0.1778 0.889)
			(layers "F.Cu" "F.Mask" "F.Paste")
			(net "GND")
		)
		(pad "53" smd rect
			(at -1.400048 -3.549904 90)
			(size 0.1778 0.889)
			(layers "F.Cu" "F.Mask" "F.Paste")
			(net "CLK_100M_DDR3_NODE1_DN")
		)
		(pad "54" smd rect
			(at -1.800098 -3.549904 90)
			(size 0.1778 0.889)
			(layers "F.Cu" "F.Mask" "F.Paste")
			(net "CLK_100M_DDR3_NODE1_DP")
		)
		(pad "55" smd rect
			(at -2.199894 -3.549904 90)
			(size 0.1778 0.889)
			(layers "F.Cu" "F.Mask" "F.Paste")
			(net "FM_CPLD_CLK_R_PG_NODE1_R")
		)
		(pad "56" smd rect
			(at -2.599944 -3.549904 90)
			(size 0.1778 0.889)
			(layers "F.Cu" "F.Mask" "F.Paste")
			(net "GND")
		)
		(pad "TH" smd rect
			(at 0 0 90)
			(size 5.7912 5.7912)
			(layers "F.Cu" "F.Mask" "F.Paste")
			(net "GND")
		)
	)
)
